# S9S_MB_2U (Grand Teton) — schematic netlist excerpt (pin names and nets, part order shuffled) for the footprints in the layout excerpt that follows; sources: Cadence DE-HDL packaged netlist, KiCad conversion of 03242023_DA0F0TMBIJ0_F0T_Motherboard_J_brd_V01_OCP.brd

R3102  Q_RES  470 1% CHIP  pkg 0402LF  page 252 : A = LED_P5V ; B = P5V
R3686  Q_RES  0 5% CHIP  pkg 0402LF  page 250 : A = P5V_ADC ; B = P5V_ADC_TIC

(kicad_pcb
	(version 20260206)
	(generator "pcbnew")
	(generator_version "10.0")
	(general
		(thickness 1.6)
		(legacy_teardrops no)
	)
	(paper "A4")
	(title_block
		(title "03242023_DA0F0TMBIJ0_F0T_Motherboard_J_brd_V01_OCP.brd")
		(comment 1 "Grand Teton / footprints 2898-2899 of 6105")
	)
	(layers
		(0 "F.Cu" signal "TOP")
		(4 "In1.Cu" signal "GND")
		(6 "In2.Cu" signal "IN1")
		(8 "In3.Cu" signal "GND1")
		(10 "In4.Cu" signal "IN2")
		(12 "In5.Cu" signal "GND2")
		(14 "In6.Cu" signal "IN3")
		(16 "In7.Cu" signal "GND3")
		(18 "In8.Cu" signal "VCC")
		(20 "In9.Cu" signal "VCC1")
		(22 "In10.Cu" signal "GND4")
		(24 "In11.Cu" signal "IN4")
		(26 "In12.Cu" signal "GND5")
		(28 "In13.Cu" signal "IN5")
		(30 "In14.Cu" signal "GND6")
		(32 "In15.Cu" signal "IN6")
		(34 "In16.Cu" signal "GND7")
		(2 "B.Cu" signal "BOTTOM")
		(9 "F.Adhes" user "F.Adhesive")
		(11 "B.Adhes" user "B.Adhesive")
		(13 "F.Paste" user "Package Geometry/Pastemask Top")
		(15 "B.Paste" user "Package Geometry/Pastemask Bottom")
		(5 "F.SilkS" user "Ref Des/Silkscreen Top")
		(7 "B.SilkS" user "Ref Des/Silkscreen Bottom")
		(1 "F.Mask" user "Board Geometry/Soldermask Top")
		(3 "B.Mask" user "Board Geometry/Soldermask Bottom")
		(17 "Dwgs.User" user "User.Drawings")
		(19 "Cmts.User" user "User.Comments")
		(21 "Eco1.User" user "User.Eco1")
		(23 "Eco2.User" user "User.Eco2")
		(25 "Edge.Cuts" user "Board Geometry/Outline")
		(27 "Margin" user)
		(31 "F.CrtYd" user "Package Geometry/Place Bound Top")
		(29 "B.CrtYd" user "Package Geometry/Place Bound Bottom")
		(35 "F.Fab" user "Ref Des/Assembly Top")
		(33 "B.Fab" user "Ref Des/Assembly Bottom")
	)
	(footprint ""
		(layer "F.Cu")
		(at 39.827454 -109.444282 180)
		(property "Reference" "R3686"
			(at 0 0 180)
			(layer "F.SilkS")
			(hide yes)
			(effects
				(font
					(size 1.27 1.27)
				)
			)
		)
		(property "Value" ""
			(at 0 0 180)
			(layer "F.Fab")
			(effects
				(font
					(size 1.27 1.27)
				)
			)
		)
		(duplicate_pad_numbers_are_jumpers no)
		(fp_line
			(start 0.7874 0.4064)
			(end -0.7874 0.4064)
			(stroke
				(width 0.1524)
				(type default)
			)
			(layer "F.SilkS")
		)
		(fp_line
			(start 0.7874 -0.4064)
			(end 0.7874 0.4064)
			(stroke
				(width 0.1524)
				(type default)
			)
			(layer "F.SilkS")
		)
		(fp_line
			(start -0.7874 0.4064)
			(end -0.7874 -0.4064)
			(stroke
				(width 0.1524)
				(type default)
			)
			(layer "F.SilkS")
		)
		(fp_line
			(start -0.7874 -0.4064)
			(end 0.7874 -0.4064)
			(stroke
				(width 0.1524)
				(type default)
			)
			(layer "F.SilkS")
		)
		(fp_line
			(start 0.67945 0.3048)
			(end 0.120396 0.3048)
			(stroke
				(width 0.1)
				(type default)
			)
			(layer "F.Fab")
		)
		(fp_line
			(start 0.67945 -0.3048)
			(end 0.67945 0.3048)
			(stroke
				(width 0.1)
				(type default)
			)
			(layer "F.Fab")
		)
		(fp_line
			(start 0.12065 -0.2794)
			(end 0.12065 -0.3048)
			(stroke
				(width 0.1)
				(type default)
			)
			(layer "F.Fab")
		)
		(fp_line
			(start 0.12065 -0.3048)
			(end 0.67945 -0.3048)
			(stroke
				(width 0.1)
				(type default)
			)
			(layer "F.Fab")
		)
		(fp_line
			(start 0.120396 0.3048)
			(end 0.120396 0.2794)
			(stroke
				(width 0.1)
				(type default)
			)
			(layer "F.Fab")
		)
		(fp_line
			(start 0.120396 0.2794)
			(end -0.12065 0.2794)
			(stroke
				(width 0.1)
				(type default)
			)
			(layer "F.Fab")
		)
		(fp_line
			(start -0.12065 0.3048)
			(end -0.67945 0.3048)
			(stroke
				(width 0.1)
				(type default)
			)
			(layer "F.Fab")
		)
		(fp_line
			(start -0.12065 0.2794)
			(end -0.12065 0.3048)
			(stroke
				(width 0.1)
				(type default)
			)
			(layer "F.Fab")
		)
		(fp_line
			(start -0.12065 -0.2794)
			(end 0.12065 -0.2794)
			(stroke
				(width 0.1)
				(type default)
			)
			(layer "F.Fab")
		)
		(fp_line
			(start -0.12065 -0.305054)
			(end -0.12065 -0.2794)
			(stroke
				(width 0.1)
				(type default)
			)
			(layer "F.Fab")
		)
		(fp_line
			(start -0.67945 0.3048)
			(end -0.67945 -0.305054)
			(stroke
				(width 0.1)
				(type default)
			)
			(layer "F.Fab")
		)
		(fp_line
			(start -0.67945 -0.305054)
			(end -0.12065 -0.305054)
			(stroke
				(width 0.1)
				(type default)
			)
			(layer "F.Fab")
		)
		(pad "1" smd rect
			(at -0.40005 0)
			(size 0.4572 0.508)
			(layers "F.Cu" "F.Mask" "F.Paste")
			(net "P5V_ADC")
		)
		(pad "2" smd rect
			(at 0.40005 0)
			(size 0.4572 0.508)
			(layers "F.Cu" "F.Mask" "F.Paste")
			(net "P5V_ADC_TIC")
		)
	)
	(footprint ""
		(layer "F.Cu")
		(at 89.95283 -74.819764 -90)
		(property "Reference" "R3102"
			(at 0 0 270)
			(layer "F.SilkS")
			(hide yes)
			(effects
				(font
					(size 1.27 1.27)
				)
			)
		)
		(property "Value" ""
			(at 0 0 270)
			(layer "F.Fab")
			(effects
				(font
					(size 1.27 1.27)
				)
			)
		)
		(duplicate_pad_numbers_are_jumpers no)
		(fp_line
			(start -0.7874 0.4064)
			(end -0.7874 -0.4064)
			(stroke
				(width 0.1524)
				(type default)
			)
			(layer "F.SilkS")
		)
		(fp_line
			(start 0.7874 0.4064)
			(end -0.7874 0.4064)
			(stroke
				(width 0.1524)
				(type default)
			)
			(layer "F.SilkS")
		)
		(fp_line
			(start -0.7874 -0.4064)
			(end 0.7874 -0.4064)
			(stroke
				(width 0.1524)
				(type default)
			)
			(layer "F.SilkS")
		)
		(fp_line
			(start 0.7874 -0.4064)
			(end 0.7874 0.4064)
			(stroke
				(width 0.1524)
				(type default)
			)
			(layer "F.SilkS")
		)
		(fp_line
			(start -0.67945 0.3048)
			(end -0.67945 -0.305054)
			(stroke
				(width 0.1)
				(type default)
			)
			(layer "F.Fab")
		)
		(fp_line
			(start -0.12065 0.3048)
			(end -0.67945 0.3048)
			(stroke
				(width 0.1)
				(type default)
			)
			(layer "F.Fab")
		)
		(fp_line
			(start 0.120396 0.3048)
			(end 0.120396 0.2794)
			(stroke
				(width 0.1)
				(type default)
			)
			(layer "F.Fab")
		)
		(fp_line
			(start 0.67945 0.3048)
			(end 0.120396 0.3048)
			(stroke
				(width 0.1)
				(type default)
			)
			(layer "F.Fab")
		)
		(fp_line
			(start -0.12065 0.2794)
			(end -0.12065 0.3048)
			(stroke
				(width 0.1)
				(type default)
			)
			(layer "F.Fab")
		)
		(fp_line
			(start 0.120396 0.2794)
			(end -0.12065 0.2794)
			(stroke
				(width 0.1)
				(type default)
			)
			(layer "F.Fab")
		)
		(fp_line
			(start -0.12065 -0.2794)
			(end 0.12065 -0.2794)
			(stroke
				(width 0.1)
				(type default)
			)
			(layer "F.Fab")
		)
		(fp_line
			(start 0.12065 -0.2794)
			(end 0.12065 -0.3048)
			(stroke
				(width 0.1)
				(type default)
			)
			(layer "F.Fab")
		)
		(fp_line
			(start 0.12065 -0.3048)
			(end 0.67945 -0.3048)
			(stroke
				(width 0.1)
				(type default)
			)
			(layer "F.Fab")
		)
		(fp_line
			(start 0.67945 -0.3048)
			(end 0.67945 0.3048)
			(stroke
				(width 0.1)
				(type default)
			)
			(layer "F.Fab")
		)
		(fp_line
			(start -0.67945 -0.305054)
			(end -0.12065 -0.305054)
			(stroke
				(width 0.1)
				(type default)
			)
			(layer "F.Fab")
		)
		(fp_line
			(start -0.12065 -0.305054)
			(end -0.12065 -0.2794)
			(stroke
				(width 0.1)
				(type default)
			)
			(layer "F.Fab")
		)
		(pad "1" smd circle
			(at -0.40005 0 270)
			(size 0 0)
			(layers "F.Cu" "F.Mask" "F.Paste")
			(net "LED_P5V")
		)
		(pad "2" smd circle
			(at 0.40005 0 270)
			(size 0 0)
			(layers "F.Cu" "F.Mask" "F.Paste")
			(net "P5V")
		)
	)
)
